# T6G (Grand Teton) — schematic netlist excerpt (pin names and nets, part order shuffled) for the footprints in the layout excerpt that follows; sources: Cadence DE-HDL packaged netlist, KiCad conversion of 04192023_DAF0TMB3IC0_F0TG_MB_C_brd_V02_OCP.brd

R2125  Q_RES  4.7K 5% CHIP  pkg 0402LF  page 145 : A = P3V3_AUX ; B = SMB_PCIE_E1S_ISO_EN
R1440  Q_RES  100K 1% CHIP  pkg 0402LF  page 259 : A = P12V_MEM_CPU1 ; B = PWRGD_P12V_MEM_CPU1_EN

(kicad_pcb
	(version 20260206)
	(generator "pcbnew")
	(generator_version "10.0")
	(general
		(thickness 1.6)
		(legacy_teardrops no)
	)
	(paper "A4")
	(title_block
		(title "04192023_DAF0TMB3IC0_F0TG_MB_C_brd_V02_OCP.brd")
		(comment 1 "Grand Teton / footprints 4060-4061 of 8354")
	)
	(layers
		(0 "F.Cu" signal "TOP")
		(4 "In1.Cu" signal "GND")
		(6 "In2.Cu" signal "IN1")
		(8 "In3.Cu" signal "GND1")
		(10 "In4.Cu" signal "IN2")
		(12 "In5.Cu" signal "GND2")
		(14 "In6.Cu" signal "IN3")
		(16 "In7.Cu" signal "GND3")
		(18 "In8.Cu" signal "VCC")
		(20 "In9.Cu" signal "VCC1")
		(22 "In10.Cu" signal "GND4")
		(24 "In11.Cu" signal "IN4")
		(26 "In12.Cu" signal "GND5")
		(28 "In13.Cu" signal "IN5")
		(30 "In14.Cu" signal "GND6")
		(32 "In15.Cu" signal "IN6")
		(34 "In16.Cu" signal "GND7")
		(2 "B.Cu" signal "BOTTOM")
		(9 "F.Adhes" user "F.Adhesive")
		(11 "B.Adhes" user "B.Adhesive")
		(13 "F.Paste" user "Package Geometry/Pastemask Top")
		(15 "B.Paste" user "Package Geometry/Pastemask Bottom")
		(5 "F.SilkS" user "Ref Des/Silkscreen Top")
		(7 "B.SilkS" user "Ref Des/Silkscreen Bottom")
		(1 "F.Mask" user "Board Geometry/Soldermask Top")
		(3 "B.Mask" user "Board Geometry/Soldermask Bottom")
		(17 "Dwgs.User" user "User.Drawings")
		(19 "Cmts.User" user "User.Comments")
		(21 "Eco1.User" user "User.Eco1")
		(23 "Eco2.User" user "User.Eco2")
		(25 "Edge.Cuts" user "Board Geometry/Outline")
		(27 "Margin" user)
		(31 "F.CrtYd" user "Package Geometry/Place Bound Top")
		(29 "B.CrtYd" user "Package Geometry/Place Bound Bottom")
		(35 "F.Fab" user "Ref Des/Assembly Top")
		(33 "B.Fab" user "Ref Des/Assembly Bottom")
	)
	(footprint ""
		(layer "F.Cu")
		(at 261.468616 -72.976994 180)
		(property "Reference" "R2125"
			(at 0 0 180)
			(layer "F.SilkS")
			(hide yes)
			(effects
				(font
					(size 1.27 1.27)
				)
			)
		)
		(property "Value" ""
			(at 0 0 180)
			(layer "F.Fab")
			(effects
				(font
					(size 1.27 1.27)
				)
			)
		)
		(duplicate_pad_numbers_are_jumpers no)
		(fp_line
			(start 0.7874 0.4064)
			(end -0.7874 0.4064)
			(stroke
				(width 0.1524)
				(type default)
			)
			(layer "F.SilkS")
		)
		(fp_line
			(start 0.7874 -0.4064)
			(end 0.7874 0.4064)
			(stroke
				(width 0.1524)
				(type default)
			)
			(layer "F.SilkS")
		)
		(fp_line
			(start -0.7874 0.4064)
			(end -0.7874 -0.4064)
			(stroke
				(width 0.1524)
				(type default)
			)
			(layer "F.SilkS")
		)
		(fp_line
			(start -0.7874 -0.4064)
			(end 0.7874 -0.4064)
			(stroke
				(width 0.1524)
				(type default)
			)
			(layer "F.SilkS")
		)
		(fp_line
			(start 0.67945 0.3048)
			(end 0.120396 0.3048)
			(stroke
				(width 0.1)
				(type default)
			)
			(layer "F.Fab")
		)
		(fp_line
			(start 0.67945 -0.3048)
			(end 0.67945 0.3048)
			(stroke
				(width 0.1)
				(type default)
			)
			(layer "F.Fab")
		)
		(fp_line
			(start 0.12065 -0.2794)
			(end 0.12065 -0.3048)
			(stroke
				(width 0.1)
				(type default)
			)
			(layer "F.Fab")
		)
		(fp_line
			(start 0.12065 -0.3048)
			(end 0.67945 -0.3048)
			(stroke
				(width 0.1)
				(type default)
			)
			(layer "F.Fab")
		)
		(fp_line
			(start 0.120396 0.3048)
			(end 0.120396 0.2794)
			(stroke
				(width 0.1)
				(type default)
			)
			(layer "F.Fab")
		)
		(fp_line
			(start 0.120396 0.2794)
			(end -0.12065 0.2794)
			(stroke
				(width 0.1)
				(type default)
			)
			(layer "F.Fab")
		)
		(fp_line
			(start -0.12065 0.3048)
			(end -0.67945 0.3048)
			(stroke
				(width 0.1)
				(type default)
			)
			(layer "F.Fab")
		)
		(fp_line
			(start -0.12065 0.2794)
			(end -0.12065 0.3048)
			(stroke
				(width 0.1)
				(type default)
			)
			(layer "F.Fab")
		)
		(fp_line
			(start -0.12065 -0.2794)
			(end 0.12065 -0.2794)
			(stroke
				(width 0.1)
				(type default)
			)
			(layer "F.Fab")
		)
		(fp_line
			(start -0.12065 -0.305054)
			(end -0.12065 -0.2794)
			(stroke
				(width 0.1)
				(type default)
			)
			(layer "F.Fab")
		)
		(fp_line
			(start -0.67945 0.3048)
			(end -0.67945 -0.305054)
			(stroke
				(width 0.1)
				(type default)
			)
			(layer "F.Fab")
		)
		(fp_line
			(start -0.67945 -0.305054)
			(end -0.12065 -0.305054)
			(stroke
				(width 0.1)
				(type default)
			)
			(layer "F.Fab")
		)
		(pad "1" smd circle
			(at -0.40005 0 180)
			(size 0 0)
			(layers "F.Cu" "F.Mask" "F.Paste")
			(net "P3V3_AUX")
		)
		(pad "2" smd circle
			(at 0.40005 0 180)
			(size 0 0)
			(layers "F.Cu" "F.Mask" "F.Paste")
			(net "SMB_PCIE_E1S_ISO_EN")
		)
	)
	(footprint ""
		(layer "F.Cu")
		(at 106.675936 -127.768096 -90)
		(property "Reference" "R1440"
			(at 0 0 270)
			(layer "F.SilkS")
			(hide yes)
			(effects
				(font
					(size 1.27 1.27)
				)
			)
		)
		(property "Value" ""
			(at 0 0 270)
			(layer "F.Fab")
			(effects
				(font
					(size 1.27 1.27)
				)
			)
		)
		(duplicate_pad_numbers_are_jumpers no)
		(fp_line
			(start -0.7874 0.4064)
			(end -0.7874 -0.4064)
			(stroke
				(width 0.1524)
				(type default)
			)
			(layer "F.SilkS")
		)
		(fp_line
			(start 0.7874 0.4064)
			(end -0.7874 0.4064)
			(stroke
				(width 0.1524)
				(type default)
			)
			(layer "F.SilkS")
		)
		(fp_line
			(start -0.7874 -0.4064)
			(end 0.7874 -0.4064)
			(stroke
				(width 0.1524)
				(type default)
			)
			(layer "F.SilkS")
		)
		(fp_line
			(start 0.7874 -0.4064)
			(end 0.7874 0.4064)
			(stroke
				(width 0.1524)
				(type default)
			)
			(layer "F.SilkS")
		)
		(fp_line
			(start -0.67945 0.3048)
			(end -0.67945 -0.305054)
			(stroke
				(width 0.1)
				(type default)
			)
			(layer "F.Fab")
		)
		(fp_line
			(start -0.12065 0.3048)
			(end -0.67945 0.3048)
			(stroke
				(width 0.1)
				(type default)
			)
			(layer "F.Fab")
		)
		(fp_line
			(start 0.120396 0.3048)
			(end 0.120396 0.2794)
			(stroke
				(width 0.1)
				(type default)
			)
			(layer "F.Fab")
		)
		(fp_line
			(start 0.67945 0.3048)
			(end 0.120396 0.3048)
			(stroke
				(width 0.1)
				(type default)
			)
			(layer "F.Fab")
		)
		(fp_line
			(start -0.12065 0.2794)
			(end -0.12065 0.3048)
			(stroke
				(width 0.1)
				(type default)
			)
			(layer "F.Fab")
		)
		(fp_line
			(start 0.120396 0.2794)
			(end -0.12065 0.2794)
			(stroke
				(width 0.1)
				(type default)
			)
			(layer "F.Fab")
		)
		(fp_line
			(start -0.12065 -0.2794)
			(end 0.12065 -0.2794)
			(stroke
				(width 0.1)
				(type default)
			)
			(layer "F.Fab")
		)
		(fp_line
			(start 0.12065 -0.2794)
			(end 0.12065 -0.3048)
			(stroke
				(width 0.1)
				(type default)
			)
			(layer "F.Fab")
		)
		(fp_line
			(start 0.12065 -0.3048)
			(end 0.67945 -0.3048)
			(stroke
				(width 0.1)
				(type default)
			)
			(layer "F.Fab")
		)
		(fp_line
			(start 0.67945 -0.3048)
			(end 0.67945 0.3048)
			(stroke
				(width 0.1)
				(type default)
			)
			(layer "F.Fab")
		)
		(fp_line
			(start -0.67945 -0.305054)
			(end -0.12065 -0.305054)
			(stroke
				(width 0.1)
				(type default)
			)
			(layer "F.Fab")
		)
		(fp_line
			(start -0.12065 -0.305054)
			(end -0.12065 -0.2794)
			(stroke
				(width 0.1)
				(type default)
			)
			(layer "F.Fab")
		)
		(pad "1" smd circle
			(at -0.40005 0 270)
			(size 0 0)
			(layers "F.Cu" "F.Mask" "F.Paste")
			(net "P12V_MEM_CPU1")
		)
		(pad "2" smd circle
			(at 0.40005 0 270)
			(size 0 0)
			(layers "F.Cu" "F.Mask" "F.Paste")
			(net "PWRGD_P12V_MEM_CPU1_EN")
		)
	)
)
